(kicad_pcb
	(version 20260206)
	(generator "pcbnew")
	(generator_version "10.0")
	(general
		(thickness 1.6)
		(legacy_teardrops no)
	)
	(paper "A4")
	(title_block
		(title "baseboard — 13948-1b.1110WZS1818.brd")
		(comment 1 "Honey Badger (Wiwynn) / footprint 852 of 2523 (SU2), pads 242-358 of 896")
	)
	(layers
		(0 "F.Cu" signal "TOP")
		(4 "In1.Cu" signal "L2GND")
		(6 "In2.Cu" signal "L3")
		(8 "In3.Cu" signal "L4VCC")
		(10 "In4.Cu" signal "L5VCC")
		(12 "In5.Cu" signal "L6")
		(14 "In6.Cu" signal "L7GND")
		(2 "B.Cu" signal "BOTTOM")
		(9 "F.Adhes" user "F.Adhesive")
		(11 "B.Adhes" user "B.Adhesive")
		(13 "F.Paste" user "Package Geometry/Pastemask Top")
		(15 "B.Paste" user "Package Geometry/Pastemask Bottom")
		(5 "F.SilkS" user "Ref Des/Silkscreen Top")
		(7 "B.SilkS" user "Ref Des/Silkscreen Bottom")
		(1 "F.Mask" user "Board Geometry/Soldermask Top")
		(3 "B.Mask" user "Board Geometry/Soldermask Bottom")
		(17 "Dwgs.User" user "User.Drawings")
		(19 "Cmts.User" user "User.Comments")
		(21 "Eco1.User" user "User.Eco1")
		(23 "Eco2.User" user "User.Eco2")
		(25 "Edge.Cuts" user "Board Geometry/Outline")
		(27 "Margin" user)
		(31 "F.CrtYd" user "Package Geometry/Place Bound Top")
		(29 "B.CrtYd" user "Package Geometry/Place Bound Bottom")
		(35 "F.Fab" user "Ref Des/Assembly Top")
		(33 "B.Fab" user "Ref Des/Assembly Bottom")
	)
	(footprint ""
		(layer "F.Cu")
		(at 102.350062 -44.99991)
		(property "Reference" "SU2"
			(at 0 0 0)
			(layer "F.SilkS")
			(hide yes)
			(effects
				(font
					(size 1.27 1.27)
				)
			)
		)
		(property "Value" "SAS3008C0-1-DB-500020657-1-GP"
			(at -20.374102 -5.0292 0)
			(unlocked yes)
			(layer "F.Fab")
			(hide yes)
			(effects
				(font
					(size 1.016 1.016)
					(thickness 0.1524)
				)
			)
		)
		(property "Device Type" "BGA896D25H78"
			(at -20.374102 -6.5532 0)
			(unlocked yes)
			(layer "F.Fab")
			(hide yes)
			(effects
				(font
					(size 1.016 1.016)
					(thickness 0.1524)
				)
			)
		)
		(duplicate_pad_numbers_are_jumpers no)
		(pad "AH4" smd circle
			(at -9.19988 9.99998)
			(size 0.3556 0.3556)
			(layers "F.Cu" "F.Mask" "F.Paste")
			(net "3008_SAS_RX_P0")
		)
		(pad "AH5" smd circle
			(at -8.400034 9.99998)
			(size 0.3556 0.3556)
			(layers "F.Cu" "F.Mask" "F.Paste")
			(net "3008_SAS_RX_N0")
		)
		(pad "AH6" smd circle
			(at -7.599934 9.99998)
			(size 0.3556 0.3556)
			(layers "F.Cu" "F.Mask" "F.Paste")
			(net "GND")
		)
		(pad "AH7" smd circle
			(at -6.800088 9.99998)
			(size 0.3556 0.3556)
			(layers "F.Cu" "F.Mask" "F.Paste")
			(net "GND")
		)
		(pad "AH8" smd circle
			(at -5.999988 9.99998)
			(size 0.3556 0.3556)
			(layers "F.Cu" "F.Mask" "F.Paste")
			(net "GND")
		)
		(pad "AH9" smd circle
			(at -5.199888 9.99998)
			(size 0.3556 0.3556)
			(layers "F.Cu" "F.Mask" "F.Paste")
			(net "GND")
		)
		(pad "AH10" smd circle
			(at -4.400042 9.99998)
			(size 0.3556 0.3556)
			(layers "F.Cu" "F.Mask" "F.Paste")
			(net "GND")
		)
		(pad "AH11" smd circle
			(at -3.599942 9.99998)
			(size 0.3556 0.3556)
			(layers "F.Cu" "F.Mask" "F.Paste")
			(net "GND")
		)
		(pad "AH12" smd circle
			(at -2.800096 9.99998)
			(size 0.3556 0.3556)
			(layers "F.Cu" "F.Mask" "F.Paste")
			(net "GND")
		)
		(pad "AH13" smd circle
			(at -1.999996 9.99998)
			(size 0.3556 0.3556)
			(layers "F.Cu" "F.Mask" "F.Paste")
			(net "GND")
		)
		(pad "AH14" smd circle
			(at -1.199896 9.99998)
			(size 0.3556 0.3556)
			(layers "F.Cu" "F.Mask" "F.Paste")
			(net "GND")
		)
		(pad "AH15" smd circle
			(at -0.40005 9.99998)
			(size 0.3556 0.3556)
			(layers "F.Cu" "F.Mask" "F.Paste")
			(net "P1V5_C")
		)
		(pad "AH16" smd circle
			(at 0.40005 9.99998)
			(size 0.3556 0.3556)
			(layers "F.Cu" "F.Mask" "F.Paste")
			(net "GND")
		)
		(pad "AH17" smd circle
			(at 1.199896 9.99998)
			(size 0.3556 0.3556)
			(layers "F.Cu" "F.Mask" "F.Paste")
			(net "GND")
		)
		(pad "AH18" smd circle
			(at 1.999996 9.99998)
			(size 0.3556 0.3556)
			(layers "F.Cu" "F.Mask" "F.Paste")
			(net "GND")
		)
		(pad "AH19" smd circle
			(at 2.800096 9.99998)
			(size 0.3556 0.3556)
			(layers "F.Cu" "F.Mask" "F.Paste")
			(net "Net_1031")
		)
		(pad "AH20" smd circle
			(at 3.599942 9.99998)
			(size 0.3556 0.3556)
			(layers "F.Cu" "F.Mask" "F.Paste")
			(net "SYS_RST_N_0")
		)
		(pad "AH21" smd circle
			(at 4.400042 9.99998)
			(size 0.3556 0.3556)
			(layers "F.Cu" "F.Mask" "F.Paste")
			(net "IOC_UART_1_TX")
		)
		(pad "AH22" smd circle
			(at 5.199888 9.99998)
			(size 0.3556 0.3556)
			(layers "F.Cu" "F.Mask" "F.Paste")
			(net "IOC_GPIO_2")
		)
		(pad "AH23" smd circle
			(at 5.999988 9.99998)
			(size 0.3556 0.3556)
			(layers "F.Cu" "F.Mask" "F.Paste")
			(net "IOC_GPIO_3")
		)
		(pad "AH24" smd circle
			(at 6.800088 9.99998)
			(size 0.3556 0.3556)
			(layers "F.Cu" "F.Mask" "F.Paste")
			(net "IOC_GPIO_5")
		)
		(pad "AH25" smd circle
			(at 7.599934 9.99998)
			(size 0.3556 0.3556)
			(layers "F.Cu" "F.Mask" "F.Paste")
			(net "IOC_GPIO_6")
		)
		(pad "AH26" smd circle
			(at 8.400034 9.99998)
			(size 0.3556 0.3556)
			(layers "F.Cu" "F.Mask" "F.Paste")
			(net "IOC_UART_1_RX")
		)
		(pad "AH27" smd circle
			(at 9.19988 9.99998)
			(size 0.3556 0.3556)
			(layers "F.Cu" "F.Mask" "F.Paste")
			(net "SPARE0")
		)
		(pad "AH28" smd circle
			(at 9.99998 9.99998)
			(size 0.4064 0.4064)
			(layers "F.Cu" "F.Mask" "F.Paste")
			(net "IOC_GPIO_10")
		)
		(pad "AH29" smd circle
			(at 10.80008 9.99998)
			(size 0.4064 0.4064)
			(layers "F.Cu" "F.Mask" "F.Paste")
			(net "IOC_GPIO_22")
		)
		(pad "AH30" smd circle
			(at 11.599926 9.99998)
			(size 0.4064 0.4064)
			(layers "F.Cu" "F.Mask" "F.Paste")
			(net "IOC_GPIO_11")
		)
		(pad "AJ1" smd circle
			(at -11.599926 10.80008)
			(size 0.4064 0.4064)
			(layers "F.Cu" "F.Mask" "F.Paste")
			(net "SAS0_VDDH")
		)
		(pad "AJ2" smd circle
			(at -10.80008 10.80008)
			(size 0.4064 0.4064)
			(layers "F.Cu" "F.Mask" "F.Paste")
			(net "GND")
		)
		(pad "AJ3" smd circle
			(at -9.99998 10.80008)
			(size 0.4064 0.4064)
			(layers "F.Cu" "F.Mask" "F.Paste")
			(net "SAS0_AVDD")
		)
		(pad "AJ4" smd circle
			(at -9.19988 10.80008)
			(size 0.3556 0.3556)
			(layers "F.Cu" "F.Mask" "F.Paste")
			(net "GND")
		)
		(pad "AJ5" smd circle
			(at -8.400034 10.80008)
			(size 0.3556 0.3556)
			(layers "F.Cu" "F.Mask" "F.Paste")
			(net "GND")
		)
		(pad "AJ6" smd circle
			(at -7.599934 10.80008)
			(size 0.3556 0.3556)
			(layers "F.Cu" "F.Mask" "F.Paste")
			(net "GND")
		)
		(pad "AJ7" smd circle
			(at -6.800088 10.80008)
			(size 0.3556 0.3556)
			(layers "F.Cu" "F.Mask" "F.Paste")
			(net "PCIE_SAS_CPU_TX_N0")
		)
		(pad "AJ8" smd circle
			(at -5.999988 10.80008)
			(size 0.3556 0.3556)
			(layers "F.Cu" "F.Mask" "F.Paste")
			(net "PCIE_SAS_CPU_TX_N1")
		)
		(pad "AJ9" smd circle
			(at -5.199888 10.80008)
			(size 0.3556 0.3556)
			(layers "F.Cu" "F.Mask" "F.Paste")
			(net "GND")
		)
		(pad "AJ10" smd circle
			(at -4.400042 10.80008)
			(size 0.3556 0.3556)
			(layers "F.Cu" "F.Mask" "F.Paste")
			(net "PCIE_SAS_CPU_TX_N2")
		)
		(pad "AJ11" smd circle
			(at -3.599942 10.80008)
			(size 0.3556 0.3556)
			(layers "F.Cu" "F.Mask" "F.Paste")
			(net "PCIE_SAS_CPU_TX_N3")
		)
		(pad "AJ12" smd circle
			(at -2.800096 10.80008)
			(size 0.3556 0.3556)
			(layers "F.Cu" "F.Mask" "F.Paste")
			(net "GND")
		)
		(pad "AJ13" smd circle
			(at -1.999996 10.80008)
			(size 0.3556 0.3556)
			(layers "F.Cu" "F.Mask" "F.Paste")
			(net "PCIE_SAS_CPU_TX_N4")
		)
		(pad "AJ14" smd circle
			(at -1.199896 10.80008)
			(size 0.3556 0.3556)
			(layers "F.Cu" "F.Mask" "F.Paste")
			(net "PCIE_SAS_CPU_TX_N5")
		)
		(pad "AJ15" smd circle
			(at -0.40005 10.80008)
			(size 0.3556 0.3556)
			(layers "F.Cu" "F.Mask" "F.Paste")
			(net "GND")
		)
		(pad "AJ16" smd circle
			(at 0.40005 10.80008)
			(size 0.3556 0.3556)
			(layers "F.Cu" "F.Mask" "F.Paste")
			(net "PCIE_SAS_CPU_TX_N6")
		)
		(pad "AJ17" smd circle
			(at 1.199896 10.80008)
			(size 0.3556 0.3556)
			(layers "F.Cu" "F.Mask" "F.Paste")
			(net "PCIE_SAS_CPU_TX_N7")
		)
		(pad "AJ18" smd circle
			(at 1.999996 10.80008)
			(size 0.3556 0.3556)
			(layers "F.Cu" "F.Mask" "F.Paste")
			(net "GND")
		)
		(pad "AJ19" smd circle
			(at 2.800096 10.80008)
			(size 0.3556 0.3556)
			(layers "F.Cu" "F.Mask" "F.Paste")
			(net "Net_1032")
		)
		(pad "AJ20" smd circle
			(at 3.599942 10.80008)
			(size 0.3556 0.3556)
			(layers "F.Cu" "F.Mask" "F.Paste")
			(net "SYS_ERR_0")
		)
		(pad "AJ21" smd circle
			(at 4.400042 10.80008)
			(size 0.3556 0.3556)
			(layers "F.Cu" "F.Mask" "F.Paste")
			(net "IOC_RESET#")
		)
		(pad "AJ22" smd circle
			(at 5.199888 10.80008)
			(size 0.3556 0.3556)
			(layers "F.Cu" "F.Mask" "F.Paste")
			(net "SPARE2")
		)
		(pad "AJ23" smd circle
			(at 5.999988 10.80008)
			(size 0.3556 0.3556)
			(layers "F.Cu" "F.Mask" "F.Paste")
			(net "SYS_DBMODE3")
		)
		(pad "AJ24" smd circle
			(at 6.800088 10.80008)
			(size 0.3556 0.3556)
			(layers "F.Cu" "F.Mask" "F.Paste")
			(net "IOC_UART_0_RX")
		)
		(pad "AJ25" smd circle
			(at 7.599934 10.80008)
			(size 0.3556 0.3556)
			(layers "F.Cu" "F.Mask" "F.Paste")
			(net "IOC_GPIO_13")
		)
		(pad "AJ26" smd circle
			(at 8.400034 10.80008)
			(size 0.3556 0.3556)
			(layers "F.Cu" "F.Mask" "F.Paste")
			(net "IOC_GPIO_1")
		)
		(pad "AJ27" smd circle
			(at 9.19988 10.80008)
			(size 0.3556 0.3556)
			(layers "F.Cu" "F.Mask" "F.Paste")
			(net "IOC_GPIO_14")
		)
		(pad "AJ28" smd circle
			(at 9.99998 10.80008)
			(size 0.4064 0.4064)
			(layers "F.Cu" "F.Mask" "F.Paste")
			(net "IOC_GPIO_20")
		)
		(pad "AJ29" smd circle
			(at 10.80008 10.80008)
			(size 0.4064 0.4064)
			(layers "F.Cu" "F.Mask" "F.Paste")
			(net "IOC_GPIO_12")
		)
		(pad "AJ30" smd circle
			(at 11.599926 10.80008)
			(size 0.4064 0.4064)
			(layers "F.Cu" "F.Mask" "F.Paste")
			(net "IOC_GPIO_4")
		)
		(pad "AK2" smd circle
			(at -10.80008 11.599926)
			(size 0.4064 0.4064)
			(layers "F.Cu" "F.Mask" "F.Paste")
			(net "GND")
		)
		(pad "AK3" smd circle
			(at -9.99998 11.599926)
			(size 0.4064 0.4064)
			(layers "F.Cu" "F.Mask" "F.Paste")
			(net "GND")
		)
		(pad "AK4" smd circle
			(at -9.19988 11.599926)
			(size 0.3556 0.3556)
			(layers "F.Cu" "F.Mask" "F.Paste")
			(net "CLK_100M_PCIE_P")
		)
		(pad "AK5" smd circle
			(at -8.400034 11.599926)
			(size 0.3556 0.3556)
			(layers "F.Cu" "F.Mask" "F.Paste")
			(net "CLK_100M_PCIE_N")
		)
		(pad "AK6" smd circle
			(at -7.599934 11.599926)
			(size 0.3556 0.3556)
			(layers "F.Cu" "F.Mask" "F.Paste")
			(net "PCE_AVDD")
		)
		(pad "AK7" smd circle
			(at -6.800088 11.599926)
			(size 0.3556 0.3556)
			(layers "F.Cu" "F.Mask" "F.Paste")
			(net "PCIE_SAS_CPU_TX_P0")
		)
		(pad "AK8" smd circle
			(at -5.999988 11.599926)
			(size 0.3556 0.3556)
			(layers "F.Cu" "F.Mask" "F.Paste")
			(net "PCIE_SAS_CPU_TX_P1")
		)
		(pad "AK9" smd circle
			(at -5.199888 11.599926)
			(size 0.3556 0.3556)
			(layers "F.Cu" "F.Mask" "F.Paste")
			(net "PCE_AVDD")
		)
		(pad "AK10" smd circle
			(at -4.400042 11.599926)
			(size 0.3556 0.3556)
			(layers "F.Cu" "F.Mask" "F.Paste")
			(net "PCIE_SAS_CPU_TX_P2")
		)
		(pad "AK11" smd circle
			(at -3.599942 11.599926)
			(size 0.3556 0.3556)
			(layers "F.Cu" "F.Mask" "F.Paste")
			(net "PCIE_SAS_CPU_TX_P3")
		)
		(pad "AK12" smd circle
			(at -2.800096 11.599926)
			(size 0.3556 0.3556)
			(layers "F.Cu" "F.Mask" "F.Paste")
			(net "PCE_AVDD")
		)
		(pad "AK13" smd circle
			(at -1.999996 11.599926)
			(size 0.3556 0.3556)
			(layers "F.Cu" "F.Mask" "F.Paste")
			(net "PCIE_SAS_CPU_TX_P4")
		)
		(pad "AK14" smd circle
			(at -1.199896 11.599926)
			(size 0.3556 0.3556)
			(layers "F.Cu" "F.Mask" "F.Paste")
			(net "PCIE_SAS_CPU_TX_P5")
		)
		(pad "AK15" smd circle
			(at -0.40005 11.599926)
			(size 0.3556 0.3556)
			(layers "F.Cu" "F.Mask" "F.Paste")
			(net "PCE_AVDD")
		)
		(pad "AK16" smd circle
			(at 0.40005 11.599926)
			(size 0.3556 0.3556)
			(layers "F.Cu" "F.Mask" "F.Paste")
			(net "PCIE_SAS_CPU_TX_P6")
		)
		(pad "AK17" smd circle
			(at 1.199896 11.599926)
			(size 0.3556 0.3556)
			(layers "F.Cu" "F.Mask" "F.Paste")
			(net "PCIE_SAS_CPU_TX_P7")
		)
		(pad "AK18" smd circle
			(at 1.999996 11.599926)
			(size 0.3556 0.3556)
			(layers "F.Cu" "F.Mask" "F.Paste")
			(net "PCE_AVDD")
		)
		(pad "AK19" smd circle
			(at 2.800096 11.599926)
			(size 0.3556 0.3556)
			(layers "F.Cu" "F.Mask" "F.Paste")
			(net "Net_1033")
		)
		(pad "AK20" smd circle
			(at 3.599942 11.599926)
			(size 0.3556 0.3556)
			(layers "F.Cu" "F.Mask" "F.Paste")
			(net "SYS_DBMODE1")
		)
		(pad "AK21" smd circle
			(at 4.400042 11.599926)
			(size 0.3556 0.3556)
			(layers "F.Cu" "F.Mask" "F.Paste")
			(net "SYS_DBMODE4")
		)
		(pad "AK22" smd circle
			(at 5.199888 11.599926)
			(size 0.3556 0.3556)
			(layers "F.Cu" "F.Mask" "F.Paste")
			(net "SYS_ERROR1")
		)
		(pad "AK23" smd circle
			(at 5.999988 11.599926)
			(size 0.3556 0.3556)
			(layers "F.Cu" "F.Mask" "F.Paste")
			(net "SYS_HALT0#")
		)
		(pad "AK24" smd circle
			(at 6.800088 11.599926)
			(size 0.3556 0.3556)
			(layers "F.Cu" "F.Mask" "F.Paste")
			(net "SYS_DBMODE2")
		)
		(pad "AK25" smd circle
			(at 7.599934 11.599926)
			(size 0.3556 0.3556)
			(layers "F.Cu" "F.Mask" "F.Paste")
			(net "SPARE1")
		)
		(pad "AK26" smd circle
			(at 8.400034 11.599926)
			(size 0.3556 0.3556)
			(layers "F.Cu" "F.Mask" "F.Paste")
			(net "SYS_HALT1#")
		)
		(pad "AK27" smd circle
			(at 9.19988 11.599926)
			(size 0.3556 0.3556)
			(layers "F.Cu" "F.Mask" "F.Paste")
			(net "IOC_UART_0_TX")
		)
		(pad "AK28" smd circle
			(at 9.99998 11.599926)
			(size 0.4064 0.4064)
			(layers "F.Cu" "F.Mask" "F.Paste")
			(net "IOC_GPIO_19")
		)
		(pad "AK29" smd circle
			(at 10.80008 11.599926)
			(size 0.4064 0.4064)
			(layers "F.Cu" "F.Mask" "F.Paste")
			(net "IOC_GPIO_9")
		)
		(pad "B1" smd circle
			(at -11.599926 -10.80008)
			(size 0.4064 0.4064)
			(layers "F.Cu" "F.Mask" "F.Paste")
			(net "Net_1072")
		)
		(pad "B2" smd circle
			(at -10.80008 -10.80008)
			(size 0.4064 0.4064)
			(layers "F.Cu" "F.Mask" "F.Paste")
			(net "GND")
		)
		(pad "B3" smd circle
			(at -9.99998 -10.80008)
			(size 0.4064 0.4064)
			(layers "F.Cu" "F.Mask" "F.Paste")
			(net "Net_1038")
		)
		(pad "B4" smd circle
			(at -9.19988 -10.80008)
			(size 0.3556 0.3556)
			(layers "F.Cu" "F.Mask" "F.Paste")
			(net "Net_1039")
		)
		(pad "B5" smd circle
			(at -8.400034 -10.80008)
			(size 0.3556 0.3556)
			(layers "F.Cu" "F.Mask" "F.Paste")
			(net "Net_1040")
		)
		(pad "B6" smd circle
			(at -7.599934 -10.80008)
			(size 0.3556 0.3556)
			(layers "F.Cu" "F.Mask" "F.Paste")
			(net "GND")
		)
		(pad "B7" smd circle
			(at -6.800088 -10.80008)
			(size 0.3556 0.3556)
			(layers "F.Cu" "F.Mask" "F.Paste")
			(net "ICE1_TCK")
		)
		(pad "B8" smd circle
			(at -5.999988 -10.80008)
			(size 0.3556 0.3556)
			(layers "F.Cu" "F.Mask" "F.Paste")
			(net "ICE0_TDI")
		)
		(pad "B9" smd circle
			(at -5.199888 -10.80008)
			(size 0.3556 0.3556)
			(layers "F.Cu" "F.Mask" "F.Paste")
			(net "IOC_VREF_SET")
		)
		(pad "B10" smd circle
			(at -4.400042 -10.80008)
			(size 0.3556 0.3556)
			(layers "F.Cu" "F.Mask" "F.Paste")
			(net "Net_1041")
		)
		(pad "B11" smd circle
			(at -3.599942 -10.80008)
			(size 0.3556 0.3556)
			(layers "F.Cu" "F.Mask" "F.Paste")
			(net "GND")
		)
		(pad "B12" smd circle
			(at -2.800096 -10.80008)
			(size 0.3556 0.3556)
			(layers "F.Cu" "F.Mask" "F.Paste")
			(net "AVSO_IDDTN18")
		)
		(pad "B13" smd circle
			(at -1.999996 -10.80008)
			(size 0.3556 0.3556)
			(layers "F.Cu" "F.Mask" "F.Paste")
			(net "AVSO_VREF")
		)
		(pad "B14" smd circle
			(at -1.199896 -10.80008)
			(size 0.3556 0.3556)
			(layers "F.Cu" "F.Mask" "F.Paste")
			(net "GND")
		)
		(pad "B15" smd circle
			(at -0.40005 -10.80008)
			(size 0.3556 0.3556)
			(layers "F.Cu" "F.Mask" "F.Paste")
			(net "GND")
		)
		(pad "B16" smd circle
			(at 0.40005 -10.80008)
			(size 0.3556 0.3556)
			(layers "F.Cu" "F.Mask" "F.Paste")
			(net "LSI_JTAG_EN_N")
		)
		(pad "B17" smd circle
			(at 1.199896 -10.80008)
			(size 0.3556 0.3556)
			(layers "F.Cu" "F.Mask" "F.Paste")
			(net "LSI_SCAN_EN")
		)
		(pad "B18" smd circle
			(at 1.999996 -10.80008)
			(size 0.3556 0.3556)
			(layers "F.Cu" "F.Mask" "F.Paste")
			(net "JTAG_IOC_TMS")
		)
		(pad "B19" smd circle
			(at 2.800096 -10.80008)
			(size 0.3556 0.3556)
			(layers "F.Cu" "F.Mask" "F.Paste")
			(net "XM_CS0_N")
		)
		(pad "B20" smd circle
			(at 3.599942 -10.80008)
			(size 0.3556 0.3556)
			(layers "F.Cu" "F.Mask" "F.Paste")
			(net "XM_F_RST_N")
		)
		(pad "B21" smd circle
			(at 4.400042 -10.80008)
			(size 0.3556 0.3556)
			(layers "F.Cu" "F.Mask" "F.Paste")
			(net "XM_NAND_CS_N")
		)
		(pad "B22" smd circle
			(at 5.199888 -10.80008)
			(size 0.3556 0.3556)
			(layers "F.Cu" "F.Mask" "F.Paste")
			(net "XM_OE_N")
		)
		(pad "B23" smd circle
			(at 5.999988 -10.80008)
			(size 0.3556 0.3556)
			(layers "F.Cu" "F.Mask" "F.Paste")
			(net "Net_1025")
		)
		(pad "B24" smd circle
			(at 6.800088 -10.80008)
			(size 0.3556 0.3556)
			(layers "F.Cu" "F.Mask" "F.Paste")
			(net "Net_1026")
		)
		(pad "B25" smd circle
			(at 7.599934 -10.80008)
			(size 0.3556 0.3556)
			(layers "F.Cu" "F.Mask" "F.Paste")
			(net "XM_ADDR_0")
		)
		(pad "B26" smd circle
			(at 8.400034 -10.80008)
			(size 0.3556 0.3556)
			(layers "F.Cu" "F.Mask" "F.Paste")
			(net "XM_ALE")
		)
		(pad "B27" smd circle
			(at 9.19988 -10.80008)
			(size 0.3556 0.3556)
			(layers "F.Cu" "F.Mask" "F.Paste")
			(net "XM_ADDR_1")
		)
		(pad "B28" smd circle
			(at 9.99998 -10.80008)
			(size 0.4064 0.4064)
			(layers "F.Cu" "F.Mask" "F.Paste")
			(net "XM_ADDR_6")
		)
		(pad "B29" smd circle
			(at 10.80008 -10.80008)
			(size 0.4064 0.4064)
			(layers "F.Cu" "F.Mask" "F.Paste")
			(net "XM_ADDR_8")
		)
		(pad "B30" smd circle
			(at 11.599926 -10.80008)
			(size 0.4064 0.4064)
			(layers "F.Cu" "F.Mask" "F.Paste")
			(net "XM_ADDR_7")
		)
		(pad "C1" smd circle
			(at -11.599926 -9.99998)
			(size 0.4064 0.4064)
			(layers "F.Cu" "F.Mask" "F.Paste")
			(net "GND")
		)
		(pad "C2" smd circle
			(at -10.80008 -9.99998)
			(size 0.4064 0.4064)
			(layers "F.Cu" "F.Mask" "F.Paste")
			(net "Net_1042")
		)
	)
)
